# S9S_MB_2U (Grand Teton) — schematic netlist excerpt (pin names and nets, part order shuffled) for the footprints in the layout excerpt that follows; sources: Cadence DE-HDL packaged netlist, KiCad conversion of 03242023_DA0F0TMBIJ0_F0T_Motherboard_J_brd_V01_OCP.brd

PC467  Q_CAP  0.1UF 25V 10% EMPTY  pkg 0402  page 292 : A = PVCCINFAON_CPU1_CSPIN ; B = GND
PR832  Q_RES  0 5% CHIP  pkg 0402LF  page 259 : A = P3V3_AUX_MODE ; B = GND

(kicad_pcb
	(version 20260206)
	(generator "pcbnew")
	(generator_version "10.0")
	(general
		(thickness 1.6)
		(legacy_teardrops no)
	)
	(paper "A4")
	(title_block
		(title "03242023_DA0F0TMBIJ0_F0T_Motherboard_J_brd_V01_OCP.brd")
		(comment 1 "Grand Teton / footprints 2339-2340 of 6105")
	)
	(layers
		(0 "F.Cu" signal "TOP")
		(4 "In1.Cu" signal "GND")
		(6 "In2.Cu" signal "IN1")
		(8 "In3.Cu" signal "GND1")
		(10 "In4.Cu" signal "IN2")
		(12 "In5.Cu" signal "GND2")
		(14 "In6.Cu" signal "IN3")
		(16 "In7.Cu" signal "GND3")
		(18 "In8.Cu" signal "VCC")
		(20 "In9.Cu" signal "VCC1")
		(22 "In10.Cu" signal "GND4")
		(24 "In11.Cu" signal "IN4")
		(26 "In12.Cu" signal "GND5")
		(28 "In13.Cu" signal "IN5")
		(30 "In14.Cu" signal "GND6")
		(32 "In15.Cu" signal "IN6")
		(34 "In16.Cu" signal "GND7")
		(2 "B.Cu" signal "BOTTOM")
		(9 "F.Adhes" user "F.Adhesive")
		(11 "B.Adhes" user "B.Adhesive")
		(13 "F.Paste" user "Package Geometry/Pastemask Top")
		(15 "B.Paste" user "Package Geometry/Pastemask Bottom")
		(5 "F.SilkS" user "Ref Des/Silkscreen Top")
		(7 "B.SilkS" user "Ref Des/Silkscreen Bottom")
		(1 "F.Mask" user "Board Geometry/Soldermask Top")
		(3 "B.Mask" user "Board Geometry/Soldermask Bottom")
		(17 "Dwgs.User" user "User.Drawings")
		(19 "Cmts.User" user "User.Comments")
		(21 "Eco1.User" user "User.Eco1")
		(23 "Eco2.User" user "User.Eco2")
		(25 "Edge.Cuts" user "Board Geometry/Outline")
		(27 "Margin" user)
		(31 "F.CrtYd" user "Package Geometry/Place Bound Top")
		(29 "B.CrtYd" user "Package Geometry/Place Bound Bottom")
		(35 "F.Fab" user "Ref Des/Assembly Top")
		(33 "B.Fab" user "Ref Des/Assembly Bottom")
	)
	(footprint ""
		(layer "F.Cu")
		(at 446.675002 -77.829918 90)
		(property "Reference" "PR832"
			(at 0 0 90)
			(layer "F.SilkS")
			(hide yes)
			(effects
				(font
					(size 1.27 1.27)
				)
			)
		)
		(property "Value" ""
			(at 0 0 90)
			(layer "F.Fab")
			(effects
				(font
					(size 1.27 1.27)
				)
			)
		)
		(duplicate_pad_numbers_are_jumpers no)
		(fp_line
			(start 0.7874 -0.4064)
			(end 0.7874 0.4064)
			(stroke
				(width 0.1524)
				(type default)
			)
			(layer "F.SilkS")
		)
		(fp_line
			(start -0.7874 -0.4064)
			(end 0.7874 -0.4064)
			(stroke
				(width 0.1524)
				(type default)
			)
			(layer "F.SilkS")
		)
		(fp_line
			(start 0.7874 0.4064)
			(end -0.7874 0.4064)
			(stroke
				(width 0.1524)
				(type default)
			)
			(layer "F.SilkS")
		)
		(fp_line
			(start -0.7874 0.4064)
			(end -0.7874 -0.4064)
			(stroke
				(width 0.1524)
				(type default)
			)
			(layer "F.SilkS")
		)
		(fp_line
			(start -0.12065 -0.305054)
			(end -0.12065 -0.2794)
			(stroke
				(width 0.1)
				(type default)
			)
			(layer "F.Fab")
		)
		(fp_line
			(start -0.67945 -0.305054)
			(end -0.12065 -0.305054)
			(stroke
				(width 0.1)
				(type default)
			)
			(layer "F.Fab")
		)
		(fp_line
			(start 0.67945 -0.3048)
			(end 0.67945 0.3048)
			(stroke
				(width 0.1)
				(type default)
			)
			(layer "F.Fab")
		)
		(fp_line
			(start 0.12065 -0.3048)
			(end 0.67945 -0.3048)
			(stroke
				(width 0.1)
				(type default)
			)
			(layer "F.Fab")
		)
		(fp_line
			(start 0.12065 -0.2794)
			(end 0.12065 -0.3048)
			(stroke
				(width 0.1)
				(type default)
			)
			(layer "F.Fab")
		)
		(fp_line
			(start -0.12065 -0.2794)
			(end 0.12065 -0.2794)
			(stroke
				(width 0.1)
				(type default)
			)
			(layer "F.Fab")
		)
		(fp_line
			(start 0.120396 0.2794)
			(end -0.12065 0.2794)
			(stroke
				(width 0.1)
				(type default)
			)
			(layer "F.Fab")
		)
		(fp_line
			(start -0.12065 0.2794)
			(end -0.12065 0.3048)
			(stroke
				(width 0.1)
				(type default)
			)
			(layer "F.Fab")
		)
		(fp_line
			(start 0.67945 0.3048)
			(end 0.120396 0.3048)
			(stroke
				(width 0.1)
				(type default)
			)
			(layer "F.Fab")
		)
		(fp_line
			(start 0.120396 0.3048)
			(end 0.120396 0.2794)
			(stroke
				(width 0.1)
				(type default)
			)
			(layer "F.Fab")
		)
		(fp_line
			(start -0.12065 0.3048)
			(end -0.67945 0.3048)
			(stroke
				(width 0.1)
				(type default)
			)
			(layer "F.Fab")
		)
		(fp_line
			(start -0.67945 0.3048)
			(end -0.67945 -0.305054)
			(stroke
				(width 0.1)
				(type default)
			)
			(layer "F.Fab")
		)
		(pad "1" smd circle
			(at -0.40005 0 90)
			(size 0 0)
			(layers "F.Cu" "F.Mask" "F.Paste")
			(net "P3V3_AUX_MODE")
		)
		(pad "2" smd circle
			(at 0.40005 0 90)
			(size 0 0)
			(layers "F.Cu" "F.Mask" "F.Paste")
			(net "GND")
		)
	)
	(footprint ""
		(layer "F.Cu")
		(at 27.0383 -129.380996 180)
		(property "Reference" "PC467"
			(at 0 0 180)
			(layer "F.SilkS")
			(hide yes)
			(effects
				(font
					(size 1.27 1.27)
				)
			)
		)
		(property "Value" ""
			(at 0 0 180)
			(layer "F.Fab")
			(effects
				(font
					(size 1.27 1.27)
				)
			)
		)
		(duplicate_pad_numbers_are_jumpers no)
		(fp_line
			(start 0.7874 0.4064)
			(end -0.7874 0.4064)
			(stroke
				(width 0.1524)
				(type default)
			)
			(layer "F.SilkS")
		)
		(fp_line
			(start 0.7874 -0.4064)
			(end 0.7874 0.4064)
			(stroke
				(width 0.1524)
				(type default)
			)
			(layer "F.SilkS")
		)
		(fp_line
			(start -0.7874 0.4064)
			(end -0.7874 -0.4064)
			(stroke
				(width 0.1524)
				(type default)
			)
			(layer "F.SilkS")
		)
		(fp_line
			(start -0.7874 -0.4064)
			(end 0.7874 -0.4064)
			(stroke
				(width 0.1524)
				(type default)
			)
			(layer "F.SilkS")
		)
		(fp_line
			(start 0.67945 0.3048)
			(end 0.120396 0.3048)
			(stroke
				(width 0.1)
				(type default)
			)
			(layer "F.Fab")
		)
		(fp_line
			(start 0.67945 -0.3048)
			(end 0.67945 0.3048)
			(stroke
				(width 0.1)
				(type default)
			)
			(layer "F.Fab")
		)
		(fp_line
			(start 0.12065 -0.2794)
			(end 0.12065 -0.3048)
			(stroke
				(width 0.1)
				(type default)
			)
			(layer "F.Fab")
		)
		(fp_line
			(start 0.12065 -0.3048)
			(end 0.67945 -0.3048)
			(stroke
				(width 0.1)
				(type default)
			)
			(layer "F.Fab")
		)
		(fp_line
			(start 0.120396 0.3048)
			(end 0.120396 0.2794)
			(stroke
				(width 0.1)
				(type default)
			)
			(layer "F.Fab")
		)
		(fp_line
			(start 0.120396 0.2794)
			(end -0.12065 0.2794)
			(stroke
				(width 0.1)
				(type default)
			)
			(layer "F.Fab")
		)
		(fp_line
			(start -0.12065 0.3048)
			(end -0.67945 0.3048)
			(stroke
				(width 0.1)
				(type default)
			)
			(layer "F.Fab")
		)
		(fp_line
			(start -0.12065 0.2794)
			(end -0.12065 0.3048)
			(stroke
				(width 0.1)
				(type default)
			)
			(layer "F.Fab")
		)
		(fp_line
			(start -0.12065 -0.2794)
			(end 0.12065 -0.2794)
			(stroke
				(width 0.1)
				(type default)
			)
			(layer "F.Fab")
		)
		(fp_line
			(start -0.12065 -0.305054)
			(end -0.12065 -0.2794)
			(stroke
				(width 0.1)
				(type default)
			)
			(layer "F.Fab")
		)
		(fp_line
			(start -0.67945 0.3048)
			(end -0.67945 -0.305054)
			(stroke
				(width 0.1)
				(type default)
			)
			(layer "F.Fab")
		)
		(fp_line
			(start -0.67945 -0.305054)
			(end -0.12065 -0.305054)
			(stroke
				(width 0.1)
				(type default)
			)
			(layer "F.Fab")
		)
		(pad "1" smd circle
			(at -0.40005 0 180)
			(size 0 0)
			(layers "F.Cu" "F.Mask" "F.Paste")
			(net "PVCCINFAON_CPU1_CSPIN")
		)
		(pad "2" smd circle
			(at 0.40005 0 180)
			(size 0 0)
			(layers "F.Cu" "F.Mask" "F.Paste")
			(net "GND")
		)
	)
)
